(kicad_pcb
	(version 20260206)
	(generator "pcbnew")
	(generator_version "10.0")
	(general
		(thickness 1.6)
		(legacy_teardrops no)
	)
	(paper "A4")
	(title_block
		(title "panther-plus-userver — 13130-1b_20150205.brd")
		(comment 1 "Honey Badger (Wiwynn) / footprints 1014-1022 of 1509")
	)
	(layers
		(0 "F.Cu" signal "TOP")
		(4 "In1.Cu" signal "L2")
		(6 "In2.Cu" signal "L3")
		(8 "In3.Cu" signal "L4")
		(10 "In4.Cu" signal "L5")
		(12 "In5.Cu" signal "L6")
		(14 "In6.Cu" signal "L7")
		(16 "In7.Cu" signal "L8")
		(18 "In8.Cu" signal "L9")
		(20 "In9.Cu" signal "L10")
		(22 "In10.Cu" signal "L11")
		(2 "B.Cu" signal "BOTTOM")
		(9 "F.Adhes" user "F.Adhesive")
		(11 "B.Adhes" user "B.Adhesive")
		(13 "F.Paste" user "Package Geometry/Pastemask Top")
		(15 "B.Paste" user "Package Geometry/Pastemask Bottom")
		(5 "F.SilkS" user "Ref Des/Silkscreen Top")
		(7 "B.SilkS" user "Ref Des/Silkscreen Bottom")
		(1 "F.Mask" user "Board Geometry/Soldermask Top")
		(3 "B.Mask" user "Board Geometry/Soldermask Bottom")
		(17 "Dwgs.User" user "User.Drawings")
		(19 "Cmts.User" user "User.Comments")
		(21 "Eco1.User" user "User.Eco1")
		(23 "Eco2.User" user "User.Eco2")
		(25 "Edge.Cuts" user "Board Geometry/Outline")
		(27 "Margin" user)
		(31 "F.CrtYd" user "Package Geometry/Place Bound Top")
		(29 "B.CrtYd" user "Package Geometry/Place Bound Bottom")
		(35 "F.Fab" user "Ref Des/Assembly Top")
		(33 "B.Fab" user "Ref Des/Assembly Bottom")
	)
	(footprint ""
		(layer "B.Cu")
		(at 36.957 -26.924 -90)
		(property "Reference" "C309"
			(at 0 0 90)
			(layer "B.SilkS")
			(hide yes)
			(effects
				(font
					(size 1.27 1.27)
				)
				(justify mirror)
			)
		)
		(property "Value" "SCD1U10V2KX-5GP"
			(at -1.8923 -1.2065 270)
			(unlocked yes)
			(layer "B.Fab")
			(hide yes)
			(effects
				(font
					(size 1.016 1.016)
					(thickness 0.1524)
				)
				(justify mirror)
			)
		)
		(property "Device Type" "C402H22"
			(at -1.8923 -2.7305 270)
			(unlocked yes)
			(layer "B.Fab")
			(hide yes)
			(effects
				(font
					(size 1.016 1.016)
					(thickness 0.1524)
				)
				(justify mirror)
			)
		)
		(duplicate_pad_numbers_are_jumpers no)
		(fp_rect
			(start 0.381 0.7366)
			(end -0.381 -0.7366)
			(stroke
				(width 0)
				(type default)
			)
			(fill no)
			(layer "B.CrtYd")
		)
		(fp_rect
			(start 0.381 0.7366)
			(end -0.381 -0.7366)
			(stroke
				(width 0)
				(type default)
			)
			(fill no)
			(layer "B.Fab")
		)
		(pad "1" smd custom
			(at 0 -0.4572 90)
			(size 0.1143 0.1143)
			(layers "B.Cu" "B.Mask" "B.Paste")
			(net "P3V3_VDD_CLKBUFF")
			(options
				(clearance outline)
				(anchor circle)
			)
			(primitives
				(gr_poly
					(pts
						(arc
							(start -0.254 0.1778)
							(mid -0.239121 0.213721)
							(end -0.2032 0.2286)
						)
						(arc
							(start 0.2032 0.2286)
							(mid 0.239121 0.213721)
							(end 0.254 0.1778)
						)
						(arc
							(start 0.254 -0.1778)
							(mid 0.239121 -0.213721)
							(end 0.2032 -0.2286)
						)
						(arc
							(start -0.2032 -0.2286)
							(mid -0.239121 -0.213721)
							(end -0.254 -0.1778)
						)
					)
					(width 0)
					(fill yes)
				)
			)
		)
		(pad "2" smd custom
			(at 0 0.4572 90)
			(size 0.1143 0.1143)
			(layers "B.Cu" "B.Mask" "B.Paste")
			(net "GND")
			(options
				(clearance outline)
				(anchor circle)
			)
			(primitives
				(gr_poly
					(pts
						(arc
							(start -0.254 0.1778)
							(mid -0.239121 0.213721)
							(end -0.2032 0.2286)
						)
						(arc
							(start 0.2032 0.2286)
							(mid 0.239121 0.213721)
							(end 0.254 0.1778)
						)
						(arc
							(start 0.254 -0.1778)
							(mid 0.239121 -0.213721)
							(end 0.2032 -0.2286)
						)
						(arc
							(start -0.2032 -0.2286)
							(mid -0.239121 -0.213721)
							(end -0.254 -0.1778)
						)
					)
					(width 0)
					(fill yes)
				)
			)
		)
	)
	(footprint ""
		(layer "B.Cu")
		(at 194.945 -31.877)
		(property "Reference" "PC102"
			(at 0 0 0)
			(layer "B.SilkS")
			(hide yes)
			(effects
				(font
					(size 1.27 1.27)
				)
				(justify mirror)
			)
		)
		(property "Value" "SC22U25V5MX-GP"
			(at 0 -4.9022 0)
			(unlocked yes)
			(layer "B.Fab")
			(hide yes)
			(effects
				(font
					(size 1.016 1.016)
					(thickness 0.1524)
				)
				(justify mirror)
			)
		)
		(property "Device Type" "C805H58"
			(at 0 -6.8072 0)
			(unlocked yes)
			(layer "B.Fab")
			(hide yes)
			(effects
				(font
					(size 1.016 1.016)
					(thickness 0.1524)
				)
				(justify mirror)
			)
		)
		(duplicate_pad_numbers_are_jumpers no)
		(fp_line
			(start -0.6096 0)
			(end 0.6096 0)
			(stroke
				(width 0.3048)
				(type default)
			)
			(layer "B.SilkS")
		)
		(fp_poly
			(pts
				(xy 0.9017 1.4351) (xy -0.9017 1.4351) (xy -0.9017 -1.4351) (xy 0.9017 -1.4351)
			)
			(stroke
				(width 0)
				(type default)
			)
			(fill no)
			(layer "B.CrtYd")
		)
		(fp_poly
			(pts
				(xy -0.9017 1.4351) (xy -0.9017 -1.4351) (xy 0.9017 -1.4351) (xy 0.9017 1.4351)
			)
			(stroke
				(width 0)
				(type default)
			)
			(fill no)
			(layer "B.Fab")
		)
		(pad "1" smd rect
			(at 0 -0.8382 180)
			(size 1.5494 0.9398)
			(layers "B.Cu" "B.Mask" "B.Paste")
			(net "VR_PVDDR_A_VIN")
		)
		(pad "2" smd rect
			(at 0 0.8382 180)
			(size 1.5494 0.9398)
			(layers "B.Cu" "B.Mask" "B.Paste")
			(net "GND")
		)
	)
	(footprint ""
		(layer "B.Cu")
		(at 102.489 -64.643 90)
		(property "Reference" "PG1"
			(at 0 0 90)
			(layer "B.SilkS")
			(hide yes)
			(effects
				(font
					(size 1.27 1.27)
				)
				(justify mirror)
			)
		)
		(property "Value" "COPPER-CLOSE-GP-U"
			(at -0.0762 -2.8702 90)
			(unlocked yes)
			(layer "B.Fab")
			(hide yes)
			(effects
				(font
					(size 1.016 1.016)
					(thickness 0.1524)
				)
				(justify mirror)
			)
		)
		(property "Device Type" "CON2C-U"
			(at -0.0762 -4.3942 90)
			(unlocked yes)
			(layer "B.Fab")
			(hide yes)
			(effects
				(font
					(size 1.016 1.016)
					(thickness 0.1524)
				)
				(justify mirror)
			)
		)
		(duplicate_pad_numbers_are_jumpers no)
		(fp_rect
			(start 0.9398 0.9652)
			(end -0.9398 -0.9652)
			(stroke
				(width 0)
				(type default)
			)
			(fill no)
			(layer "B.CrtYd")
		)
		(fp_rect
			(start 0.9398 0.9652)
			(end -0.9398 -0.9652)
			(stroke
				(width 0)
				(type default)
			)
			(fill no)
			(layer "B.Fab")
		)
		(pad "1" smd custom
			(at 0 -0.5334 270)
			(size 0.17145 0.17145)
			(layers "B.Cu" "B.Mask" "B.Paste")
			(net "AGND_P1V1")
			(options
				(clearance outline)
				(anchor circle)
			)
			(primitives
				(gr_poly
					(pts
						(xy -0.127 -0.3429) (xy -0.127 -0.1651) (xy -0.635 0.3429) (xy 0.635 0.3429) (xy 0.127 -0.1651)
						(xy 0.127 -0.3429)
					)
					(width 0)
					(fill yes)
				)
			)
		)
		(pad "2" smd custom
			(at 0 0.5334 270)
			(size 0.17145 0.17145)
			(layers "B.Cu" "B.Mask" "B.Paste")
			(net "GND")
			(options
				(clearance outline)
				(anchor circle)
			)
			(primitives
				(gr_poly
					(pts
						(xy -0.635 -0.3429) (xy -0.127 0.1651) (xy -0.127 0.3429) (xy 0.127 0.3429) (xy 0.127 0.1651)
						(xy 0.635 -0.3429)
					)
					(width 0)
					(fill yes)
				)
			)
		)
	)
	(footprint ""
		(layer "B.Cu")
		(at 134.366 -47.879 90)
		(property "Reference" "R399"
			(at 0 0 90)
			(layer "B.SilkS")
			(hide yes)
			(effects
				(font
					(size 1.27 1.27)
				)
				(justify mirror)
			)
		)
		(property "Value" "0R2J-2-GP"
			(at -1.7907 -1.1176 90)
			(unlocked yes)
			(layer "B.Fab")
			(hide yes)
			(effects
				(font
					(size 1.016 1.016)
					(thickness 0.1524)
				)
				(justify mirror)
			)
		)
		(property "Device Type" "R402H16"
			(at -1.7907 -2.6416 90)
			(unlocked yes)
			(layer "B.Fab")
			(hide yes)
			(effects
				(font
					(size 1.016 1.016)
					(thickness 0.1524)
				)
				(justify mirror)
			)
		)
		(duplicate_pad_numbers_are_jumpers no)
		(fp_rect
			(start 0.381 0.8382)
			(end -0.381 -0.8382)
			(stroke
				(width 0)
				(type default)
			)
			(fill no)
			(layer "B.CrtYd")
		)
		(fp_rect
			(start 0.381 0.8382)
			(end -0.381 -0.8382)
			(stroke
				(width 0)
				(type default)
			)
			(fill no)
			(layer "B.Fab")
		)
		(pad "1" smd custom
			(at 0 -0.4318 270)
			(size 0.127 0.127)
			(layers "B.Cu" "B.Mask" "B.Paste")
			(net "REV_CPU_FPGA_IO1")
			(options
				(clearance outline)
				(anchor circle)
			)
			(primitives
				(gr_poly
					(pts
						(arc
							(start -0.2032 0.2794)
							(mid -0.239121 0.264521)
							(end -0.254 0.2286)
						)
						(arc
							(start -0.254 -0.2286)
							(mid -0.239121 -0.264521)
							(end -0.2032 -0.2794)
						)
						(arc
							(start 0.2032 -0.2794)
							(mid 0.239121 -0.264521)
							(end 0.254 -0.2286)
						)
						(arc
							(start 0.254 0.2286)
							(mid 0.239121 0.264521)
							(end 0.2032 0.2794)
						)
					)
					(width 0)
					(fill yes)
				)
			)
		)
		(pad "2" smd custom
			(at 0 0.4318 270)
			(size 0.127 0.127)
			(layers "B.Cu" "B.Mask" "B.Paste")
			(net "REV_CPU_FPGA_R_IO1")
			(options
				(clearance outline)
				(anchor circle)
			)
			(primitives
				(gr_poly
					(pts
						(arc
							(start -0.2032 0.2794)
							(mid -0.239121 0.264521)
							(end -0.254 0.2286)
						)
						(arc
							(start -0.254 -0.2286)
							(mid -0.239121 -0.264521)
							(end -0.2032 -0.2794)
						)
						(arc
							(start 0.2032 -0.2794)
							(mid 0.239121 -0.264521)
							(end 0.254 -0.2286)
						)
						(arc
							(start 0.254 0.2286)
							(mid 0.239121 0.264521)
							(end 0.2032 0.2794)
						)
					)
					(width 0)
					(fill yes)
				)
			)
		)
	)
	(footprint ""
		(layer "B.Cu")
		(at 132.08 -59.944)
		(property "Reference" "R227"
			(at 0 0 0)
			(layer "B.SilkS")
			(hide yes)
			(effects
				(font
					(size 1.27 1.27)
				)
				(justify mirror)
			)
		)
		(property "Value" "4K7R2F-GP"
			(at -0.064008 -3.993896 0)
			(unlocked yes)
			(layer "B.Fab")
			(hide yes)
			(effects
				(font
					(size 1.016 1.016)
					(thickness 0.1524)
				)
				(justify mirror)
			)
		)
		(property "Device Type" "R402H16"
			(at -0.064008 -5.517896 0)
			(unlocked yes)
			(layer "B.Fab")
			(hide yes)
			(effects
				(font
					(size 1.016 1.016)
					(thickness 0.1524)
				)
				(justify mirror)
			)
		)
		(duplicate_pad_numbers_are_jumpers no)
		(fp_rect
			(start 0.381 0.8382)
			(end -0.381 -0.8382)
			(stroke
				(width 0)
				(type default)
			)
			(fill no)
			(layer "B.CrtYd")
		)
		(fp_rect
			(start 0.381 0.8382)
			(end -0.381 -0.8382)
			(stroke
				(width 0)
				(type default)
			)
			(fill no)
			(layer "B.Fab")
		)
		(pad "1" smd custom
			(at 0 -0.4318 180)
			(size 0.127 0.127)
			(layers "B.Cu" "B.Mask" "B.Paste")
			(net "P3V3_STBY")
			(options
				(clearance outline)
				(anchor circle)
			)
			(primitives
				(gr_poly
					(pts
						(arc
							(start -0.2032 0.2794)
							(mid -0.239121 0.264521)
							(end -0.254 0.2286)
						)
						(arc
							(start -0.254 -0.2286)
							(mid -0.239121 -0.264521)
							(end -0.2032 -0.2794)
						)
						(arc
							(start 0.2032 -0.2794)
							(mid 0.239121 -0.264521)
							(end 0.254 -0.2286)
						)
						(arc
							(start 0.254 0.2286)
							(mid 0.239121 0.264521)
							(end 0.2032 0.2794)
						)
					)
					(width 0)
					(fill yes)
				)
			)
		)
		(pad "2" smd custom
			(at 0 0.4318 180)
			(size 0.127 0.127)
			(layers "B.Cu" "B.Mask" "B.Paste")
			(net "CHA_0_SA1")
			(options
				(clearance outline)
				(anchor circle)
			)
			(primitives
				(gr_poly
					(pts
						(arc
							(start -0.2032 0.2794)
							(mid -0.239121 0.264521)
							(end -0.254 0.2286)
						)
						(arc
							(start -0.254 -0.2286)
							(mid -0.239121 -0.264521)
							(end -0.2032 -0.2794)
						)
						(arc
							(start 0.2032 -0.2794)
							(mid 0.239121 -0.264521)
							(end 0.254 -0.2286)
						)
						(arc
							(start 0.254 0.2286)
							(mid 0.239121 0.264521)
							(end 0.2032 0.2794)
						)
					)
					(width 0)
					(fill yes)
				)
			)
		)
	)
	(footprint ""
		(layer "B.Cu")
		(at 170.0784 -12.879578 180)
		(property "Reference" "C365"
			(at 0 0 0)
			(layer "B.SilkS")
			(hide yes)
			(effects
				(font
					(size 1.27 1.27)
				)
				(justify mirror)
			)
		)
		(property "Value" "SC47U6D3V5MX-1-GP"
			(at 0 -4.9022 180)
			(unlocked yes)
			(layer "B.Fab")
			(hide yes)
			(effects
				(font
					(size 1.016 1.016)
					(thickness 0.1524)
				)
				(justify mirror)
			)
		)
		(property "Device Type" "C805H54"
			(at 0 -6.8072 180)
			(unlocked yes)
			(layer "B.Fab")
			(hide yes)
			(effects
				(font
					(size 1.016 1.016)
					(thickness 0.1524)
				)
				(justify mirror)
			)
		)
		(duplicate_pad_numbers_are_jumpers no)
		(fp_line
			(start -0.6096 0)
			(end 0.6096 0)
			(stroke
				(width 0.3048)
				(type default)
			)
			(layer "B.SilkS")
		)
		(fp_poly
			(pts
				(xy 0.9017 1.4351) (xy -0.9017 1.4351) (xy -0.9017 -1.4351) (xy 0.9017 -1.4351)
			)
			(stroke
				(width 0)
				(type default)
			)
			(fill no)
			(layer "B.CrtYd")
		)
		(fp_poly
			(pts
				(xy -0.9017 1.4351) (xy -0.9017 -1.4351) (xy 0.9017 -1.4351) (xy 0.9017 1.4351)
			)
			(stroke
				(width 0)
				(type default)
			)
			(fill no)
			(layer "B.Fab")
		)
		(pad "1" smd rect
			(at 0 -0.8382)
			(size 1.5494 0.9398)
			(layers "B.Cu" "B.Mask" "B.Paste")
			(net "PV_VDDR")
		)
		(pad "2" smd rect
			(at 0 0.8382)
			(size 1.5494 0.9398)
			(layers "B.Cu" "B.Mask" "B.Paste")
			(net "GND")
		)
	)
	(footprint ""
		(layer "B.Cu")
		(at 80.264 -32.8168 90)
		(property "Reference" "R365"
			(at 0 0 90)
			(layer "B.SilkS")
			(hide yes)
			(effects
				(font
					(size 1.27 1.27)
				)
				(justify mirror)
			)
		)
		(property "Value" "0R2J-2-GP"
			(at -0.064008 -3.993896 90)
			(unlocked yes)
			(layer "B.Fab")
			(hide yes)
			(effects
				(font
					(size 1.016 1.016)
					(thickness 0.1524)
				)
				(justify mirror)
			)
		)
		(property "Device Type" "R402H16"
			(at -0.064008 -5.517896 90)
			(unlocked yes)
			(layer "B.Fab")
			(hide yes)
			(effects
				(font
					(size 1.016 1.016)
					(thickness 0.1524)
				)
				(justify mirror)
			)
		)
		(duplicate_pad_numbers_are_jumpers no)
		(fp_rect
			(start 0.381 0.8382)
			(end -0.381 -0.8382)
			(stroke
				(width 0)
				(type default)
			)
			(fill no)
			(layer "B.CrtYd")
		)
		(fp_rect
			(start 0.381 0.8382)
			(end -0.381 -0.8382)
			(stroke
				(width 0)
				(type default)
			)
			(fill no)
			(layer "B.Fab")
		)
		(pad "1" smd custom
			(at 0 -0.4318 270)
			(size 0.127 0.127)
			(layers "B.Cu" "B.Mask" "B.Paste")
			(net "GBE_SMBALRT#")
			(options
				(clearance outline)
				(anchor circle)
			)
			(primitives
				(gr_poly
					(pts
						(arc
							(start -0.2032 0.2794)
							(mid -0.239121 0.264521)
							(end -0.254 0.2286)
						)
						(arc
							(start -0.254 -0.2286)
							(mid -0.239121 -0.264521)
							(end -0.2032 -0.2794)
						)
						(arc
							(start 0.2032 -0.2794)
							(mid 0.239121 -0.264521)
							(end 0.254 -0.2286)
						)
						(arc
							(start 0.254 0.2286)
							(mid 0.239121 0.264521)
							(end 0.2032 0.2794)
						)
					)
					(width 0)
					(fill yes)
				)
			)
		)
		(pad "2" smd custom
			(at 0 0.4318 270)
			(size 0.127 0.127)
			(layers "B.Cu" "B.Mask" "B.Paste")
			(net "GND")
			(options
				(clearance outline)
				(anchor circle)
			)
			(primitives
				(gr_poly
					(pts
						(arc
							(start -0.2032 0.2794)
							(mid -0.239121 0.264521)
							(end -0.254 0.2286)
						)
						(arc
							(start -0.254 -0.2286)
							(mid -0.239121 -0.264521)
							(end -0.2032 -0.2794)
						)
						(arc
							(start 0.2032 -0.2794)
							(mid 0.239121 -0.264521)
							(end 0.254 -0.2286)
						)
						(arc
							(start 0.254 0.2286)
							(mid 0.239121 0.264521)
							(end 0.2032 0.2794)
						)
					)
					(width 0)
					(fill yes)
				)
			)
		)
	)
	(footprint ""
		(layer "B.Cu")
		(at 69.215 -61.722)
		(property "Reference" "C80"
			(at 0 0 0)
			(layer "B.SilkS")
			(hide yes)
			(effects
				(font
					(size 1.27 1.27)
				)
				(justify mirror)
			)
		)
		(property "Value" "SCD1U25V2KX-2-GP"
			(at -1.8923 -1.2065 0)
			(unlocked yes)
			(layer "B.Fab")
			(hide yes)
			(effects
				(font
					(size 1.016 1.016)
					(thickness 0.1524)
				)
				(justify mirror)
			)
		)
		(property "Device Type" "C402H22"
			(at -1.8923 -2.7305 0)
			(unlocked yes)
			(layer "B.Fab")
			(hide yes)
			(effects
				(font
					(size 1.016 1.016)
					(thickness 0.1524)
				)
				(justify mirror)
			)
		)
		(duplicate_pad_numbers_are_jumpers no)
		(fp_rect
			(start 0.381 0.7366)
			(end -0.381 -0.7366)
			(stroke
				(width 0)
				(type default)
			)
			(fill no)
			(layer "B.CrtYd")
		)
		(fp_rect
			(start 0.381 0.7366)
			(end -0.381 -0.7366)
			(stroke
				(width 0)
				(type default)
			)
			(fill no)
			(layer "B.Fab")
		)
		(pad "1" smd custom
			(at 0 -0.4572 180)
			(size 0.1143 0.1143)
			(layers "B.Cu" "B.Mask" "B.Paste")
			(net "P12V_SENSE")
			(options
				(clearance outline)
				(anchor circle)
			)
			(primitives
				(gr_poly
					(pts
						(arc
							(start -0.254 0.1778)
							(mid -0.239121 0.213721)
							(end -0.2032 0.2286)
						)
						(arc
							(start 0.2032 0.2286)
							(mid 0.239121 0.213721)
							(end 0.254 0.1778)
						)
						(arc
							(start 0.254 -0.1778)
							(mid 0.239121 -0.213721)
							(end 0.2032 -0.2286)
						)
						(arc
							(start -0.2032 -0.2286)
							(mid -0.239121 -0.213721)
							(end -0.254 -0.1778)
						)
					)
					(width 0)
					(fill yes)
				)
			)
		)
		(pad "2" smd custom
			(at 0 0.4572 180)
			(size 0.1143 0.1143)
			(layers "B.Cu" "B.Mask" "B.Paste")
			(net "GND")
			(options
				(clearance outline)
				(anchor circle)
			)
			(primitives
				(gr_poly
					(pts
						(arc
							(start -0.254 0.1778)
							(mid -0.239121 0.213721)
							(end -0.2032 0.2286)
						)
						(arc
							(start 0.2032 0.2286)
							(mid 0.239121 0.213721)
							(end 0.254 0.1778)
						)
						(arc
							(start 0.254 -0.1778)
							(mid 0.239121 -0.213721)
							(end 0.2032 -0.2286)
						)
						(arc
							(start -0.2032 -0.2286)
							(mid -0.239121 -0.213721)
							(end -0.254 -0.1778)
						)
					)
					(width 0)
					(fill yes)
				)
			)
		)
	)
	(footprint ""
		(layer "B.Cu")
		(at 46.99 -42.164)
		(property "Reference" "C36"
			(at 0 0 0)
			(layer "B.SilkS")
			(hide yes)
			(effects
				(font
					(size 1.27 1.27)
				)
				(justify mirror)
			)
		)
		(property "Value" "SC10U6D3V3MX-GP"
			(at 0 -2.8194 0)
			(unlocked yes)
			(layer "B.Fab")
			(hide yes)
			(effects
				(font
					(size 1.016 1.016)
					(thickness 0.1524)
				)
				(justify mirror)
			)
		)
		(property "Device Type" "C603H38"
			(at 0 -4.3434 0)
			(unlocked yes)
			(layer "B.Fab")
			(hide yes)
			(effects
				(font
					(size 1.016 1.016)
					(thickness 0.1524)
				)
				(justify mirror)
			)
		)
		(duplicate_pad_numbers_are_jumpers no)
		(fp_line
			(start 0.4064 0)
			(end -0.4064 0)
			(stroke
				(width 0.2286)
				(type default)
			)
			(layer "B.SilkS")
		)
		(fp_rect
			(start 0.635 1.1811)
			(end -0.635 -1.1811)
			(stroke
				(width 0)
				(type default)
			)
			(fill no)
			(layer "B.CrtYd")
		)
		(fp_rect
			(start 0.635 1.1811)
			(end -0.635 -1.1811)
			(stroke
				(width 0)
				(type default)
			)
			(fill no)
			(layer "B.Fab")
		)
		(pad "1" smd custom
			(at 0 -0.6604 180)
			(size 0.19685 0.19685)
			(layers "B.Cu" "B.Mask" "B.Paste")
			(net "P1V5_CLK_VDD_CORE")
			(options
				(clearance outline)
				(anchor circle)
			)
			(primitives
				(gr_poly
					(pts
						(arc
							(start 0.508 0.2921)
							(mid 0.478242 0.363942)
							(end 0.4064 0.3937)
						)
						(arc
							(start -0.4064 0.3937)
							(mid -0.478242 0.363942)
							(end -0.508 0.2921)
						)
						(arc
							(start -0.508 -0.2921)
							(mid -0.478242 -0.363942)
							(end -0.4064 -0.3937)
						)
						(arc
							(start 0.4064 -0.3937)
							(mid 0.478242 -0.363942)
							(end 0.508 -0.2921)
						)
					)
					(width 0)
					(fill yes)
				)
			)
		)
		(pad "2" smd custom
			(at 0 0.6604 180)
			(size 0.19685 0.19685)
			(layers "B.Cu" "B.Mask" "B.Paste")
			(net "GND")
			(options
				(clearance outline)
				(anchor circle)
			)
			(primitives
				(gr_poly
					(pts
						(arc
							(start 0.508 0.2921)
							(mid 0.478242 0.363942)
							(end 0.4064 0.3937)
						)
						(arc
							(start -0.4064 0.3937)
							(mid -0.478242 0.363942)
							(end -0.508 0.2921)
						)
						(arc
							(start -0.508 -0.2921)
							(mid -0.478242 -0.363942)
							(end -0.4064 -0.3937)
						)
						(arc
							(start 0.4064 -0.3937)
							(mid 0.478242 -0.363942)
							(end 0.508 -0.2921)
						)
					)
					(width 0)
					(fill yes)
				)
			)
		)
	)
)
